# BASEBOARD_FAB2 (Tioga Pass) — schematic netlist excerpt (pin names and nets, part order shuffled) for the footprints in the layout excerpt that follows; sources: Cadence DE-HDL packaged netlist, KiCad conversion of Wiwynn_Tioga_Pass_MB.brd

R7E22  RES  0.0 5% CHIP  pkg 0402  page 108 : A = FM_PWRBRK_N ; B = FM_PWRBRK_SLOT_N
C3T2  CAP_A  47UF 4V 20% X5R  pkg 0603V  page 194 : A = P1V8_MCP_CPU0 ; B = GND
R1U36  RES  33.2 1% CHIP  pkg 0402  page 152 : A = H_CPU1_MEMGHJ_MEMHOT_LVT3_K_N ; B = H_CPU1_MEMGHJ_MEMHOT_LVT3_N

(kicad_pcb
	(version 20260206)
	(generator "pcbnew")
	(generator_version "10.0")
	(general
		(thickness 1.6)
		(legacy_teardrops no)
	)
	(paper "A4")
	(title_block
		(title "Wiwynn_Tioga_Pass_MB.brd")
		(comment 1 "Tioga Pass / footprints 4607-4609 of 4770")
	)
	(layers
		(0 "F.Cu" signal "TOP")
		(4 "In1.Cu" signal "L2GND")
		(6 "In2.Cu" signal "L3")
		(8 "In3.Cu" signal "L4GND")
		(10 "In4.Cu" signal "L5")
		(12 "In5.Cu" signal "L6GND")
		(14 "In6.Cu" signal "L7VCC")
		(16 "In7.Cu" signal "L8VCC")
		(18 "In8.Cu" signal "L9GND")
		(20 "In9.Cu" signal "L10")
		(22 "In10.Cu" signal "L11GND")
		(24 "In11.Cu" signal "L12")
		(26 "In12.Cu" signal "L13GND")
		(2 "B.Cu" signal "BOTTOM")
		(9 "F.Adhes" user "F.Adhesive")
		(11 "B.Adhes" user "B.Adhesive")
		(13 "F.Paste" user "Package Geometry/Pastemask Top")
		(15 "B.Paste" user "Package Geometry/Pastemask Bottom")
		(5 "F.SilkS" user "Ref Des/Silkscreen Top")
		(7 "B.SilkS" user "Ref Des/Silkscreen Bottom")
		(1 "F.Mask" user "Board Geometry/Soldermask Top")
		(3 "B.Mask" user "Board Geometry/Soldermask Bottom")
		(17 "Dwgs.User" user "User.Drawings")
		(19 "Cmts.User" user "User.Comments")
		(21 "Eco1.User" user "User.Eco1")
		(23 "Eco2.User" user "User.Eco2")
		(25 "Edge.Cuts" user "Board Geometry/Outline")
		(27 "Margin" user)
		(31 "F.CrtYd" user "Package Geometry/Place Bound Top")
		(29 "B.CrtYd" user "Package Geometry/Place Bound Bottom")
		(35 "F.Fab" user "Ref Des/Assembly Top")
		(33 "B.Fab" user "Ref Des/Assembly Bottom")
	)
	(footprint ""
		(layer "B.Cu")
		(at 429.046894 -16.042894 -90)
		(property "Reference" "R1U36"
			(at 0 0 90)
			(layer "B.SilkS")
			(hide yes)
			(effects
				(font
					(size 1.27 1.27)
				)
				(justify mirror)
			)
		)
		(property "Value" ""
			(at 0 0 90)
			(layer "B.Fab")
			(effects
				(font
					(size 1.27 1.27)
				)
				(justify mirror)
			)
		)
		(duplicate_pad_numbers_are_jumpers no)
		(fp_poly
			(pts
				(xy 0.2794 -0.1016) (xy -0.2794 -0.1016) (xy -0.2794 0.9906) (xy 0.2794 0.9906)
			)
			(stroke
				(width 0)
				(type default)
			)
			(fill no)
			(layer "B.CrtYd")
		)
		(fp_line
			(start -0.2794 0.9906)
			(end -0.2794 -0.1016)
			(stroke
				(width 0.1)
				(type default)
			)
			(layer "B.Fab")
		)
		(fp_line
			(start 0.2794 0.9906)
			(end -0.2794 0.9906)
			(stroke
				(width 0.1)
				(type default)
			)
			(layer "B.Fab")
		)
		(fp_line
			(start -0.2794 -0.1016)
			(end 0.2794 -0.1016)
			(stroke
				(width 0.1)
				(type default)
			)
			(layer "B.Fab")
		)
		(fp_line
			(start 0.2794 -0.1016)
			(end 0.2794 0.9906)
			(stroke
				(width 0.1)
				(type default)
			)
			(layer "B.Fab")
		)
		(pad "1" smd rect
			(at 0 0 90)
			(size 0.508 0.508)
			(layers "B.Cu" "B.Mask" "B.Paste")
			(net "H_CPU1_MEMGHJ_MEMHOT_LVT3_K_N")
		)
		(pad "2" smd rect
			(at 0 0.889 90)
			(size 0.508 0.508)
			(layers "B.Cu" "B.Mask" "B.Paste")
			(net "H_CPU1_MEMGHJ_MEMHOT_LVT3_N")
		)
		(zone
			(layer "B.Cu")
			(hatch none 0.5)
			(connect_pads
				(clearance 0)
			)
			(min_thickness 0.25)
			(keepout
				(tracks not_allowed)
				(vias allowed)
				(pads allowed)
				(copperpour not_allowed)
				(footprints allowed)
			)
			(placement
				(enabled no)
				(sheetname "")
			)
			(fill
				(thermal_gap 0.5)
				(thermal_bridge_width 0.5)
				(island_removal_mode 0)
			)
			(polygon
				(pts
					(xy 428.411894 -15.788894) (xy 428.411894 -16.296894) (xy 428.792894 -16.296894) (xy 428.792894 -15.788894)
				)
			)
		)
		(zone
			(layer "B.Cu")
			(hatch none 0.5)
			(connect_pads
				(clearance 0)
			)
			(min_thickness 0.25)
			(keepout
				(tracks allowed)
				(vias not_allowed)
				(pads allowed)
				(copperpour not_allowed)
				(footprints allowed)
			)
			(placement
				(enabled no)
				(sheetname "")
			)
			(fill
				(thermal_gap 0.5)
				(thermal_bridge_width 0.5)
				(island_removal_mode 0)
			)
			(polygon
				(pts
					(xy 428.792894 -15.788894) (xy 428.792894 -16.296894) (xy 428.411894 -16.296894) (xy 428.411894 -15.788894)
				)
			)
		)
	)
	(footprint ""
		(layer "B.Cu")
		(at 333.659226 -38.259766 90)
		(property "Reference" "C3T2"
			(at 0 0 90)
			(layer "B.SilkS")
			(hide yes)
			(effects
				(font
					(size 1.27 1.27)
				)
				(justify mirror)
			)
		)
		(property "Value" ""
			(at 0 0 90)
			(layer "B.Fab")
			(effects
				(font
					(size 1.27 1.27)
				)
				(justify mirror)
			)
		)
		(duplicate_pad_numbers_are_jumpers no)
		(fp_rect
			(start 0.500126 1.598422)
			(end -0.500126 -0.201422)
			(stroke
				(width 0)
				(type default)
			)
			(fill no)
			(layer "B.CrtYd")
		)
		(fp_line
			(start 0.500126 -0.201422)
			(end -0.500126 -0.201422)
			(stroke
				(width 0.1)
				(type default)
			)
			(layer "B.Fab")
		)
		(fp_line
			(start -0.500126 -0.201422)
			(end -0.500126 1.598422)
			(stroke
				(width 0.1)
				(type default)
			)
			(layer "B.Fab")
		)
		(fp_line
			(start 0.500126 1.598422)
			(end 0.500126 -0.201422)
			(stroke
				(width 0.1)
				(type default)
			)
			(layer "B.Fab")
		)
		(fp_line
			(start -0.500126 1.598422)
			(end 0.500126 1.598422)
			(stroke
				(width 0.1)
				(type default)
			)
			(layer "B.Fab")
		)
		(pad "1" smd rect
			(at 0 0)
			(size 0.889 0.9906)
			(layers "B.Cu" "B.Mask" "B.Paste")
			(net "P1V8_MCP_CPU0")
		)
		(pad "2" smd rect
			(at 0 1.397)
			(size 0.889 0.9906)
			(layers "B.Cu" "B.Mask" "B.Paste")
			(net "GND")
		)
		(zone
			(layer "B.Cu")
			(hatch none 0.5)
			(connect_pads
				(clearance 0)
			)
			(min_thickness 0.25)
			(keepout
				(tracks allowed)
				(vias not_allowed)
				(pads allowed)
				(copperpour not_allowed)
				(footprints allowed)
			)
			(placement
				(enabled no)
				(sheetname "")
			)
			(fill
				(thermal_gap 0.5)
				(thermal_bridge_width 0.5)
				(island_removal_mode 0)
			)
			(polygon
				(pts
					(xy 334.611726 -38.755066) (xy 334.103726 -38.755066) (xy 334.103726 -37.764466) (xy 334.611726 -37.764466)
				)
			)
		)
		(zone
			(layer "B.Cu")
			(hatch none 0.5)
			(connect_pads
				(clearance 0)
			)
			(min_thickness 0.25)
			(keepout
				(tracks not_allowed)
				(vias allowed)
				(pads allowed)
				(copperpour not_allowed)
				(footprints allowed)
			)
			(placement
				(enabled no)
				(sheetname "")
			)
			(fill
				(thermal_gap 0.5)
				(thermal_bridge_width 0.5)
				(island_removal_mode 0)
			)
			(polygon
				(pts
					(xy 334.611726 -38.755066) (xy 334.103726 -38.755066) (xy 334.103726 -37.764466) (xy 334.611726 -37.764466)
				)
			)
		)
	)
	(footprint ""
		(layer "B.Cu")
		(at 467.868 -4.3815)
		(property "Reference" "R7E22"
			(at 0 0 0)
			(layer "B.SilkS")
			(hide yes)
			(effects
				(font
					(size 1.27 1.27)
				)
				(justify mirror)
			)
		)
		(property "Value" ""
			(at 0 0 0)
			(layer "B.Fab")
			(effects
				(font
					(size 1.27 1.27)
				)
				(justify mirror)
			)
		)
		(duplicate_pad_numbers_are_jumpers no)
		(fp_poly
			(pts
				(xy 0.2794 -0.1016) (xy -0.2794 -0.1016) (xy -0.2794 0.9906) (xy 0.2794 0.9906)
			)
			(stroke
				(width 0)
				(type default)
			)
			(fill no)
			(layer "B.CrtYd")
		)
		(fp_line
			(start -0.2794 -0.1016)
			(end 0.2794 -0.1016)
			(stroke
				(width 0.1)
				(type default)
			)
			(layer "B.Fab")
		)
		(fp_line
			(start -0.2794 0.9906)
			(end -0.2794 -0.1016)
			(stroke
				(width 0.1)
				(type default)
			)
			(layer "B.Fab")
		)
		(fp_line
			(start 0.2794 -0.1016)
			(end 0.2794 0.9906)
			(stroke
				(width 0.1)
				(type default)
			)
			(layer "B.Fab")
		)
		(fp_line
			(start 0.2794 0.9906)
			(end -0.2794 0.9906)
			(stroke
				(width 0.1)
				(type default)
			)
			(layer "B.Fab")
		)
		(pad "1" smd rect
			(at 0 0 180)
			(size 0.508 0.508)
			(layers "B.Cu" "B.Mask" "B.Paste")
			(net "FM_PWRBRK_N")
		)
		(pad "2" smd rect
			(at 0 0.889 180)
			(size 0.508 0.508)
			(layers "B.Cu" "B.Mask" "B.Paste")
			(net "FM_PWRBRK_SLOT_N")
		)
		(zone
			(layer "B.Cu")
			(hatch none 0.5)
			(connect_pads
				(clearance 0)
			)
			(min_thickness 0.25)
			(keepout
				(tracks allowed)
				(vias not_allowed)
				(pads allowed)
				(copperpour not_allowed)
				(footprints allowed)
			)
			(placement
				(enabled no)
				(sheetname "")
			)
			(fill
				(thermal_gap 0.5)
				(thermal_bridge_width 0.5)
				(island_removal_mode 0)
			)
			(polygon
				(pts
					(xy 468.122 -4.1275) (xy 467.614 -4.1275) (xy 467.614 -3.7465) (xy 468.122 -3.7465)
				)
			)
		)
		(zone
			(layer "B.Cu")
			(hatch none 0.5)
			(connect_pads
				(clearance 0)
			)
			(min_thickness 0.25)
			(keepout
				(tracks not_allowed)
				(vias allowed)
				(pads allowed)
				(copperpour not_allowed)
				(footprints allowed)
			)
			(placement
				(enabled no)
				(sheetname "")
			)
			(fill
				(thermal_gap 0.5)
				(thermal_bridge_width 0.5)
				(island_removal_mode 0)
			)
			(polygon
				(pts
					(xy 468.122 -3.7465) (xy 467.614 -3.7465) (xy 467.614 -4.1275) (xy 468.122 -4.1275)
				)
			)
		)
	)
)
